(kicad_pcb
	(version 20260206)
	(generator "pcbnew")
	(generator_version "10.0")
	(general
		(thickness 1.21888)
		(legacy_teardrops no)
	)
	(paper "A4")
	(title_block
		(title "timecard-beta-v1 — TimeCard-DC-V1.PcbDoc")
		(comment 1 "Time Appliance Project (Time Card) / footprints 60-66 of 120")
	)
	(layers
		(0 "F.Cu" signal "TOP")
		(4 "In1.Cu" signal "SGND")
		(6 "In2.Cu" signal "IN1")
		(8 "In3.Cu" signal "IN2")
		(10 "In4.Cu" signal "SGND1")
		(2 "B.Cu" signal "BOTTOM")
		(9 "F.Adhes" user "F.Adhesive")
		(11 "B.Adhes" user "B.Adhesive")
		(13 "F.Paste" user "Top Paste")
		(15 "B.Paste" user "Bottom Paste")
		(5 "F.SilkS" user "Top Overlay")
		(7 "B.SilkS" user "Bottom Overlay")
		(1 "F.Mask" user "Top Solder")
		(3 "B.Mask" user "Bottom Solder")
		(17 "Dwgs.User" user "User.Drawings")
		(19 "Cmts.User" user "User.Comments")
		(21 "Eco1.User" user "User.Eco1")
		(23 "Eco2.User" user "User.Eco2")
		(25 "Edge.Cuts" user)
		(27 "Margin" user)
		(31 "F.CrtYd" user "Top Courtyard")
		(29 "B.CrtYd" user "Bottom Courtyard")
		(35 "F.Fab" user "Top Component Center")
		(33 "B.Fab" user "Bottom Component Center")
	)
	(footprint "IntegratedCircuits:SOIC127P600X175-8N"
		(layer "F.Cu")
		(at 217.361595 101.7506 180)
		(property "Reference" "U2"
			(at 6.13379 -2.264855 0)
			(unlocked yes)
			(layer "F.SilkS")
			(effects
				(font
					(size 0.762 0.762)
					(thickness 0.2286)
				)
				(justify left bottom)
			)
		)
		(property "Value" "MP1482DS-LF"
			(at -12.7381 8.69061 0)
			(unlocked yes)
			(layer "F.SilkS")
			(hide yes)
			(effects
				(font
					(size 1.524 1.524)
					(thickness 0.254)
				)
				(justify left bottom)
			)
		)
		(sheetname "POWER")
		(sheetfile "POWER.kicad_sch")
		(duplicate_pad_numbers_are_jumpers no)
		(fp_line
			(start 2 2.5)
			(end -2 2.5)
			(stroke
				(width 0.12)
				(type solid)
			)
			(layer "F.SilkS")
		)
		(fp_line
			(start 2 -2.5)
			(end -3.4 -2.5)
			(stroke
				(width 0.12)
				(type solid)
			)
			(layer "F.SilkS")
		)
		(pad "1" smd rect
			(at -2.475 -1.905 180)
			(size 1.97 0.57)
			(layers "F.Cu" "F.Mask" "F.Paste")
			(net "NetC3_1")
		)
		(pad "2" smd rect
			(at -2.475 -0.635 180)
			(size 1.97 0.57)
			(layers "F.Cu" "F.Mask" "F.Paste")
			(net "+12V")
		)
		(pad "3" smd rect
			(at -2.475 0.635 180)
			(size 1.97 0.57)
			(layers "F.Cu" "F.Mask" "F.Paste")
			(net "NetC3_2")
		)
		(pad "4" smd rect
			(at -2.475 1.905 180)
			(size 1.97 0.57)
			(layers "F.Cu" "F.Mask" "F.Paste")
			(net "GND")
		)
		(pad "5" smd rect
			(at 2.475 1.905 180)
			(size 1.97 0.57)
			(layers "F.Cu" "F.Mask" "F.Paste")
			(net "NetR5_1")
		)
		(pad "6" smd rect
			(at 2.475 0.635 180)
			(size 1.97 0.57)
			(layers "F.Cu" "F.Mask" "F.Paste")
			(net "NetC22_2")
		)
		(pad "7" smd rect
			(at 2.475 -0.635 180)
			(size 1.97 0.57)
			(layers "F.Cu" "F.Mask" "F.Paste")
			(net "NetR3_1")
		)
		(pad "8" smd rect
			(at 2.475 -1.905 180)
			(size 1.97 0.57)
			(layers "F.Cu" "F.Mask" "F.Paste")
			(net "NetC21_2")
		)
	)
	(footprint "Vault:FP-BMX160-MFG"
		(layer "F.Cu")
		(at 140.738595 88.8286)
		(property "Reference" "U13"
			(at -0.7714 -2.723079 0)
			(unlocked yes)
			(layer "F.SilkS")
			(effects
				(font
					(size 0.762 0.762)
					(thickness 0.2286)
				)
			)
		)
		(property "Value" "BMX160"
			(at 1.967145 3.521202 0)
			(unlocked yes)
			(layer "F.SilkS")
			(hide yes)
			(effects
				(font
					(size 1.524 1.524)
					(thickness 0.254)
				)
			)
		)
		(sheetname "GPS_IMU_SENSORS")
		(sheetfile "GPS_IMU_SENSORS.kicad_sch")
		(duplicate_pad_numbers_are_jumpers no)
		(fp_line
			(start -2.1 -1.85)
			(end 2.1 -1.85)
			(stroke
				(width 0.2)
				(type solid)
			)
			(layer "F.SilkS")
		)
		(fp_line
			(start -2.1 1.85)
			(end -2.1 -1.85)
			(stroke
				(width 0.2)
				(type solid)
			)
			(layer "F.SilkS")
		)
		(fp_line
			(start -2.1 1.85)
			(end 2.1 1.85)
			(stroke
				(width 0.2)
				(type solid)
			)
			(layer "F.SilkS")
		)
		(fp_line
			(start 2.1 1.85)
			(end 2.1 -1.85)
			(stroke
				(width 0.2)
				(type solid)
			)
			(layer "F.SilkS")
		)
		(fp_circle
			(center -2.475 -0.75)
			(end -2.475 -0.875)
			(stroke
				(width 0.25)
				(type solid)
			)
			(fill no)
			(layer "F.SilkS")
		)
		(fp_line
			(start -2.1 -1.85)
			(end 2.1 -1.85)
			(stroke
				(width 0.2)
				(type solid)
			)
			(layer "F.CrtYd")
		)
		(fp_line
			(start -2.1 1.85)
			(end -2.1 -1.85)
			(stroke
				(width 0.2)
				(type solid)
			)
			(layer "F.CrtYd")
		)
		(fp_line
			(start -2.1 1.85)
			(end 2.1 1.85)
			(stroke
				(width 0.2)
				(type solid)
			)
			(layer "F.CrtYd")
		)
		(fp_line
			(start 2.1 1.85)
			(end 2.1 -1.85)
			(stroke
				(width 0.2)
				(type solid)
			)
			(layer "F.CrtYd")
		)
		(fp_line
			(start -2.1 -1.85)
			(end 2.1 -1.85)
			(stroke
				(width 0.2)
				(type solid)
			)
			(layer "F.Fab")
		)
		(fp_line
			(start -2.1 1.85)
			(end -2.1 -1.85)
			(stroke
				(width 0.2)
				(type solid)
			)
			(layer "F.Fab")
		)
		(fp_line
			(start -2.1 1.85)
			(end 2.1 1.85)
			(stroke
				(width 0.2)
				(type solid)
			)
			(layer "F.Fab")
		)
		(fp_line
			(start -0.5 0)
			(end 0.5 0)
			(stroke
				(width 0.1)
				(type solid)
			)
			(layer "F.Fab")
		)
		(fp_line
			(start 0 0.5)
			(end 0 -0.5)
			(stroke
				(width 0.1)
				(type solid)
			)
			(layer "F.Fab")
		)
		(fp_line
			(start 2.1 1.85)
			(end 2.1 -1.85)
			(stroke
				(width 0.2)
				(type solid)
			)
			(layer "F.Fab")
		)
		(fp_text user "${REFERENCE}"
			(at -0.00001 0.09602 0)
			(unlocked yes)
			(layer "F.Fab")
			(effects
				(font
					(face "Arial")
					(size 0.63 0.63)
					(thickness 0.1)
				)
				(justify left bottom)
			)
		)
		(pad "1" smd rect
			(at -1.2625 -0.75)
			(size 0.675 0.25)
			(layers "F.Cu" "F.Mask" "F.Paste")
			(net "GND")
			(solder_mask_margin 0)
			(solder_paste_margin 0)
		)
		(pad "2" smd rect
			(at -1.2625 -0.25)
			(size 0.675 0.25)
			(layers "F.Cu" "F.Mask" "F.Paste")
			(net "GND")
			(solder_mask_margin 0)
			(solder_paste_margin 0)
		)
		(pad "3" smd rect
			(at -1.2625 0.25)
			(size 0.675 0.25)
			(layers "F.Cu" "F.Mask" "F.Paste")
			(net "GND")
			(solder_mask_margin 0)
			(solder_paste_margin 0)
		)
		(pad "4" smd rect
			(at -1.2625 0.75)
			(size 0.675 0.25)
			(layers "F.Cu" "F.Mask" "F.Paste")
			(solder_mask_margin 0)
			(solder_paste_margin 0)
		)
		(pad "5" smd rect
			(at -0.5 1.0125)
			(size 0.25 0.675)
			(layers "F.Cu" "F.Mask" "F.Paste")
			(net "+3.3V")
			(solder_mask_margin 0)
			(solder_paste_margin 0)
		)
		(pad "6" smd rect
			(at 0 1.0125)
			(size 0.25 0.675)
			(layers "F.Cu" "F.Mask" "F.Paste")
			(net "GND")
			(solder_mask_margin 0)
			(solder_paste_margin 0)
		)
		(pad "7" smd rect
			(at 0.5 1.0125)
			(size 0.25 0.675)
			(layers "F.Cu" "F.Mask" "F.Paste")
			(net "GND")
			(solder_mask_margin 0)
			(solder_paste_margin 0)
		)
		(pad "8" smd rect
			(at 1.2625 0.75)
			(size 0.675 0.25)
			(layers "F.Cu" "F.Mask" "F.Paste")
			(net "+3.3V")
			(solder_mask_margin 0)
			(solder_paste_margin 0)
		)
		(pad "9" smd rect
			(at 1.2625 0.25)
			(size 0.675 0.25)
			(layers "F.Cu" "F.Mask" "F.Paste")
			(solder_mask_margin 0)
			(solder_paste_margin 0)
		)
		(pad "10" smd rect
			(at 1.2625 -0.25)
			(size 0.675 0.25)
			(layers "F.Cu" "F.Mask" "F.Paste")
			(solder_mask_margin 0)
			(solder_paste_margin 0)
		)
		(pad "11" smd rect
			(at 1.2625 -0.75)
			(size 0.675 0.25)
			(layers "F.Cu" "F.Mask" "F.Paste")
			(solder_mask_margin 0)
			(solder_paste_margin 0)
		)
		(pad "12" smd rect
			(at 0.5 -1.0125)
			(size 0.25 0.675)
			(layers "F.Cu" "F.Mask" "F.Paste")
			(net "+3.3V")
			(solder_mask_margin 0)
			(solder_paste_margin 0)
		)
		(pad "13" smd rect
			(at 0 -1.0125)
			(size 0.25 0.675)
			(layers "F.Cu" "F.Mask" "F.Paste")
			(net "SCL")
			(solder_mask_margin 0)
			(solder_paste_margin 0)
		)
		(pad "14" smd rect
			(at -0.5 -1.0125)
			(size 0.25 0.675)
			(layers "F.Cu" "F.Mask" "F.Paste")
			(net "SDA")
			(solder_mask_margin 0)
			(solder_paste_margin 0)
		)
	)
	(footprint "Passives:SOT65P210X110-3N"
		(layer "F.Cu")
		(at 97.988595 69.0786 180)
		(property "Reference" "D5"
			(at 1.75 -2.593345 0)
			(unlocked yes)
			(layer "F.SilkS")
			(effects
				(font
					(size 0.762 0.762)
					(thickness 0.2286)
				)
				(justify left bottom)
			)
		)
		(property "Value" "BAT54SW"
			(at 1.5875 -3.88239 0)
			(unlocked yes)
			(layer "F.SilkS")
			(hide yes)
			(effects
				(font
					(size 1.524 1.524)
					(thickness 0.254)
				)
				(justify left bottom)
			)
		)
		(sheetname "PCIe_JTAG")
		(sheetfile "PCIe_JTAG.kicad_sch")
		(duplicate_pad_numbers_are_jumpers no)
		(fp_line
			(start 0.675 1.1)
			(end -0.325 1.1)
			(stroke
				(width 0.2)
				(type solid)
			)
			(layer "F.SilkS")
		)
		(fp_line
			(start 0.675 0.65)
			(end 0.675 1.1)
			(stroke
				(width 0.2)
				(type solid)
			)
			(layer "F.SilkS")
		)
		(fp_line
			(start 0.675 -1.1)
			(end 0.675 -0.65)
			(stroke
				(width 0.2)
				(type solid)
			)
			(layer "F.SilkS")
		)
		(fp_line
			(start 0.675 -1.1)
			(end -0.325 -1.1)
			(stroke
				(width 0.2)
				(type solid)
			)
			(layer "F.SilkS")
		)
		(fp_circle
			(center -1.125 -1.45)
			(end -1.125 -1.325)
			(stroke
				(width 0.25)
				(type solid)
			)
			(fill no)
			(layer "F.SilkS")
		)
		(pad "1" smd rect
			(at -1.125 -0.65 270)
			(size 0.5 0.9)
			(layers "F.Cu" "F.Mask" "F.Paste")
			(net "GND")
		)
		(pad "2" smd rect
			(at -1.125 0.65 270)
			(size 0.5 0.9)
			(layers "F.Cu" "F.Mask" "F.Paste")
			(net "+3.3V")
		)
		(pad "3" smd rect
			(at 1.125 0 270)
			(size 0.5 0.9)
			(layers "F.Cu" "F.Mask" "F.Paste")
			(net "FPGA_TCK")
		)
	)
	(footprint "Passives:SOT65P210X110-3N"
		(layer "F.Cu")
		(at 107.113595 69.0786 180)
		(property "Reference" "D7"
			(at 1.5 -2.593345 0)
			(unlocked yes)
			(layer "F.SilkS")
			(effects
				(font
					(size 0.762 0.762)
					(thickness 0.2286)
				)
				(justify left bottom)
			)
		)
		(property "Value" "BAT54SW"
			(at 1.1125 -2.10739 0)
			(unlocked yes)
			(layer "F.SilkS")
			(hide yes)
			(effects
				(font
					(size 1.524 1.524)
					(thickness 0.254)
				)
				(justify left bottom)
			)
		)
		(sheetname "PCIe_JTAG")
		(sheetfile "PCIe_JTAG.kicad_sch")
		(duplicate_pad_numbers_are_jumpers no)
		(fp_line
			(start 0.675 1.1)
			(end -0.325 1.1)
			(stroke
				(width 0.2)
				(type solid)
			)
			(layer "F.SilkS")
		)
		(fp_line
			(start 0.675 0.65)
			(end 0.675 1.1)
			(stroke
				(width 0.2)
				(type solid)
			)
			(layer "F.SilkS")
		)
		(fp_line
			(start 0.675 -1.1)
			(end 0.675 -0.65)
			(stroke
				(width 0.2)
				(type solid)
			)
			(layer "F.SilkS")
		)
		(fp_line
			(start 0.675 -1.1)
			(end -0.325 -1.1)
			(stroke
				(width 0.2)
				(type solid)
			)
			(layer "F.SilkS")
		)
		(fp_circle
			(center -1.125 -1.45)
			(end -1.125 -1.325)
			(stroke
				(width 0.25)
				(type solid)
			)
			(fill no)
			(layer "F.SilkS")
		)
		(pad "1" smd rect
			(at -1.125 -0.65 270)
			(size 0.5 0.9)
			(layers "F.Cu" "F.Mask" "F.Paste")
			(net "GND")
		)
		(pad "2" smd rect
			(at -1.125 0.65 270)
			(size 0.5 0.9)
			(layers "F.Cu" "F.Mask" "F.Paste")
			(net "+3.3V")
		)
		(pad "3" smd rect
			(at 1.125 0 270)
			(size 0.5 0.9)
			(layers "F.Cu" "F.Mask" "F.Paste")
			(net "FPGA_TMS")
		)
	)
	(footprint "Vault:CAPC1608X87X45ML20T05"
		(layer "F.Cu")
		(at 86.188595 132.5286 180)
		(property "Reference" "C28"
			(at -2.77141 0.026921 180)
			(unlocked yes)
			(layer "F.SilkS")
			(effects
				(font
					(size 0.762 0.762)
					(thickness 0.2286)
				)
			)
		)
		(property "Value" "0.1uF"
			(at 2.09443 2.657602 180)
			(unlocked yes)
			(layer "F.SilkS")
			(hide yes)
			(effects
				(font
					(size 1.524 1.524)
					(thickness 0.254)
				)
			)
		)
		(sheetname "USER_IO")
		(sheetfile "USER_IO.kicad_sch")
		(duplicate_pad_numbers_are_jumpers no)
		(pad "1" smd rect
			(at -0.70001 0 270)
			(size 1.1 1.05)
			(layers "F.Cu" "F.Mask" "F.Paste")
			(net "+3.3V")
		)
		(pad "2" smd rect
			(at 0.69999 0 270)
			(size 1.1 1.05)
			(layers "F.Cu" "F.Mask" "F.Paste")
			(net "GND")
		)
	)
	(footprint "Passives:SOT65P210X110-3N"
		(layer "F.Cu")
		(at 111.613595 69.0786 180)
		(property "Reference" "D8"
			(at 1.5 -2.593345 0)
			(unlocked yes)
			(layer "F.SilkS")
			(effects
				(font
					(size 0.762 0.762)
					(thickness 0.2286)
				)
				(justify left bottom)
			)
		)
		(property "Value" "BAT54SW"
			(at 1.5875 -3.88239 0)
			(unlocked yes)
			(layer "F.SilkS")
			(hide yes)
			(effects
				(font
					(size 1.524 1.524)
					(thickness 0.254)
				)
				(justify left bottom)
			)
		)
		(sheetname "PCIe_JTAG")
		(sheetfile "PCIe_JTAG.kicad_sch")
		(duplicate_pad_numbers_are_jumpers no)
		(fp_line
			(start 0.675 1.1)
			(end -0.325 1.1)
			(stroke
				(width 0.2)
				(type solid)
			)
			(layer "F.SilkS")
		)
		(fp_line
			(start 0.675 0.65)
			(end 0.675 1.1)
			(stroke
				(width 0.2)
				(type solid)
			)
			(layer "F.SilkS")
		)
		(fp_line
			(start 0.675 -1.1)
			(end 0.675 -0.65)
			(stroke
				(width 0.2)
				(type solid)
			)
			(layer "F.SilkS")
		)
		(fp_line
			(start 0.675 -1.1)
			(end -0.325 -1.1)
			(stroke
				(width 0.2)
				(type solid)
			)
			(layer "F.SilkS")
		)
		(fp_circle
			(center -1.125 -1.45)
			(end -1.125 -1.325)
			(stroke
				(width 0.25)
				(type solid)
			)
			(fill no)
			(layer "F.SilkS")
		)
		(pad "1" smd rect
			(at -1.125 -0.65 270)
			(size 0.5 0.9)
			(layers "F.Cu" "F.Mask" "F.Paste")
			(net "GND")
		)
		(pad "2" smd rect
			(at -1.125 0.65 270)
			(size 0.5 0.9)
			(layers "F.Cu" "F.Mask" "F.Paste")
			(net "+3.3V")
		)
		(pad "3" smd rect
			(at 1.125 0 270)
			(size 0.5 0.9)
			(layers "F.Cu" "F.Mask" "F.Paste")
			(net "FPGA_TDI")
		)
	)
	(footprint "Vault:CAPC1608X87X45ML20T05"
		(layer "F.Cu")
		(at 149.613595 144.1786)
		(property "Reference" "C63"
			(at -4.8 0.193345 0)
			(unlocked yes)
			(layer "F.SilkS")
			(effects
				(font
					(size 0.762 0.762)
					(thickness 0.2286)
				)
				(justify left bottom)
			)
		)
		(property "Value" "0.1uF"
			(at -0.2921 3.47599 0)
			(unlocked yes)
			(layer "F.SilkS")
			(hide yes)
			(effects
				(font
					(size 1.524 1.524)
					(thickness 0.254)
				)
				(justify left bottom)
			)
		)
		(sheetname "MAC")
		(sheetfile "MAC.kicad_sch")
		(duplicate_pad_numbers_are_jumpers no)
		(pad "1" smd rect
			(at -0.7 0 90)
			(size 1.1 1.05)
			(layers "F.Cu" "F.Mask" "F.Paste")
			(net "GND")
		)
		(pad "2" smd rect
			(at 0.7 0 90)
			(size 1.1 1.05)
			(layers "F.Cu" "F.Mask" "F.Paste")
			(net "+5.0V")
		)
	)
)
